# T6G (Grand Teton) — schematic netlist excerpt (pin names and nets, part order shuffled) for the footprints in the layout excerpt that follows; sources: Cadence DE-HDL packaged netlist, KiCad conversion of 04192023_DAF0TMB3IC0_F0TG_MB_C_brd_V02_OCP.brd

PC578_8  Q_CAP  0.1UF 25V 10% X7R  pkg 0402  page 198 : A = PVDDCR_CPU0_P0_VCCS ; B = GND
C2024  Q_CAP  0.1UF 25V 10% X7R  pkg 0402  page 236 : A = P3V3_OCP_SFF_R ; B = GND

(kicad_pcb
	(version 20260206)
	(generator "pcbnew")
	(generator_version "10.0")
	(general
		(thickness 1.6)
		(legacy_teardrops no)
	)
	(paper "A4")
	(title_block
		(title "04192023_DAF0TMB3IC0_F0TG_MB_C_brd_V02_OCP.brd")
		(comment 1 "Grand Teton / footprints 2455-2456 of 8354")
	)
	(layers
		(0 "F.Cu" signal "TOP")
		(4 "In1.Cu" signal "GND")
		(6 "In2.Cu" signal "IN1")
		(8 "In3.Cu" signal "GND1")
		(10 "In4.Cu" signal "IN2")
		(12 "In5.Cu" signal "GND2")
		(14 "In6.Cu" signal "IN3")
		(16 "In7.Cu" signal "GND3")
		(18 "In8.Cu" signal "VCC")
		(20 "In9.Cu" signal "VCC1")
		(22 "In10.Cu" signal "GND4")
		(24 "In11.Cu" signal "IN4")
		(26 "In12.Cu" signal "GND5")
		(28 "In13.Cu" signal "IN5")
		(30 "In14.Cu" signal "GND6")
		(32 "In15.Cu" signal "IN6")
		(34 "In16.Cu" signal "GND7")
		(2 "B.Cu" signal "BOTTOM")
		(9 "F.Adhes" user "F.Adhesive")
		(11 "B.Adhes" user "B.Adhesive")
		(13 "F.Paste" user "Package Geometry/Pastemask Top")
		(15 "B.Paste" user "Package Geometry/Pastemask Bottom")
		(5 "F.SilkS" user "Ref Des/Silkscreen Top")
		(7 "B.SilkS" user "Ref Des/Silkscreen Bottom")
		(1 "F.Mask" user "Board Geometry/Soldermask Top")
		(3 "B.Mask" user "Board Geometry/Soldermask Bottom")
		(17 "Dwgs.User" user "User.Drawings")
		(19 "Cmts.User" user "User.Comments")
		(21 "Eco1.User" user "User.Eco1")
		(23 "Eco2.User" user "User.Eco2")
		(25 "Edge.Cuts" user "Board Geometry/Outline")
		(27 "Margin" user)
		(31 "F.CrtYd" user "Package Geometry/Place Bound Top")
		(29 "B.CrtYd" user "Package Geometry/Place Bound Bottom")
		(35 "F.Fab" user "Ref Des/Assembly Top")
		(33 "B.Fab" user "Ref Des/Assembly Bottom")
	)
	(footprint ""
		(layer "F.Cu")
		(at 408.841702 -163.736274 -90)
		(property "Reference" "PC578_8"
			(at 0 0 270)
			(layer "F.SilkS")
			(hide yes)
			(effects
				(font
					(size 1.27 1.27)
				)
			)
		)
		(property "Value" ""
			(at 0 0 270)
			(layer "F.Fab")
			(effects
				(font
					(size 1.27 1.27)
				)
			)
		)
		(duplicate_pad_numbers_are_jumpers no)
		(fp_line
			(start -0.7874 0.4064)
			(end -0.7874 -0.4064)
			(stroke
				(width 0.1524)
				(type default)
			)
			(layer "F.SilkS")
		)
		(fp_line
			(start 0.7874 0.4064)
			(end -0.7874 0.4064)
			(stroke
				(width 0.1524)
				(type default)
			)
			(layer "F.SilkS")
		)
		(fp_line
			(start -0.7874 -0.4064)
			(end 0.7874 -0.4064)
			(stroke
				(width 0.1524)
				(type default)
			)
			(layer "F.SilkS")
		)
		(fp_line
			(start 0.7874 -0.4064)
			(end 0.7874 0.4064)
			(stroke
				(width 0.1524)
				(type default)
			)
			(layer "F.SilkS")
		)
		(fp_line
			(start -0.67945 0.3048)
			(end -0.67945 -0.305054)
			(stroke
				(width 0.1)
				(type default)
			)
			(layer "F.Fab")
		)
		(fp_line
			(start -0.12065 0.3048)
			(end -0.67945 0.3048)
			(stroke
				(width 0.1)
				(type default)
			)
			(layer "F.Fab")
		)
		(fp_line
			(start 0.120396 0.3048)
			(end 0.120396 0.2794)
			(stroke
				(width 0.1)
				(type default)
			)
			(layer "F.Fab")
		)
		(fp_line
			(start 0.67945 0.3048)
			(end 0.120396 0.3048)
			(stroke
				(width 0.1)
				(type default)
			)
			(layer "F.Fab")
		)
		(fp_line
			(start -0.12065 0.2794)
			(end -0.12065 0.3048)
			(stroke
				(width 0.1)
				(type default)
			)
			(layer "F.Fab")
		)
		(fp_line
			(start 0.120396 0.2794)
			(end -0.12065 0.2794)
			(stroke
				(width 0.1)
				(type default)
			)
			(layer "F.Fab")
		)
		(fp_line
			(start -0.12065 -0.2794)
			(end 0.12065 -0.2794)
			(stroke
				(width 0.1)
				(type default)
			)
			(layer "F.Fab")
		)
		(fp_line
			(start 0.12065 -0.2794)
			(end 0.12065 -0.3048)
			(stroke
				(width 0.1)
				(type default)
			)
			(layer "F.Fab")
		)
		(fp_line
			(start 0.12065 -0.3048)
			(end 0.67945 -0.3048)
			(stroke
				(width 0.1)
				(type default)
			)
			(layer "F.Fab")
		)
		(fp_line
			(start 0.67945 -0.3048)
			(end 0.67945 0.3048)
			(stroke
				(width 0.1)
				(type default)
			)
			(layer "F.Fab")
		)
		(fp_line
			(start -0.67945 -0.305054)
			(end -0.12065 -0.305054)
			(stroke
				(width 0.1)
				(type default)
			)
			(layer "F.Fab")
		)
		(fp_line
			(start -0.12065 -0.305054)
			(end -0.12065 -0.2794)
			(stroke
				(width 0.1)
				(type default)
			)
			(layer "F.Fab")
		)
		(pad "1" smd circle
			(at -0.40005 0 270)
			(size 0 0)
			(layers "F.Cu" "F.Mask" "F.Paste")
			(net "PVDDCR_CPU0_P0_VCCS")
		)
		(pad "2" smd circle
			(at 0.40005 0 270)
			(size 0 0)
			(layers "F.Cu" "F.Mask" "F.Paste")
			(net "GND")
		)
	)
	(footprint ""
		(layer "F.Cu")
		(at 437.515 -94.071948 90)
		(property "Reference" "C2024"
			(at 0 0 90)
			(layer "F.SilkS")
			(hide yes)
			(effects
				(font
					(size 1.27 1.27)
				)
			)
		)
		(property "Value" ""
			(at 0 0 90)
			(layer "F.Fab")
			(effects
				(font
					(size 1.27 1.27)
				)
			)
		)
		(duplicate_pad_numbers_are_jumpers no)
		(fp_line
			(start 0.7874 -0.4064)
			(end 0.7874 0.4064)
			(stroke
				(width 0.1524)
				(type default)
			)
			(layer "F.SilkS")
		)
		(fp_line
			(start -0.7874 -0.4064)
			(end 0.7874 -0.4064)
			(stroke
				(width 0.1524)
				(type default)
			)
			(layer "F.SilkS")
		)
		(fp_line
			(start 0.7874 0.4064)
			(end -0.7874 0.4064)
			(stroke
				(width 0.1524)
				(type default)
			)
			(layer "F.SilkS")
		)
		(fp_line
			(start -0.7874 0.4064)
			(end -0.7874 -0.4064)
			(stroke
				(width 0.1524)
				(type default)
			)
			(layer "F.SilkS")
		)
		(fp_line
			(start -0.12065 -0.305054)
			(end -0.12065 -0.2794)
			(stroke
				(width 0.1)
				(type default)
			)
			(layer "F.Fab")
		)
		(fp_line
			(start -0.67945 -0.305054)
			(end -0.12065 -0.305054)
			(stroke
				(width 0.1)
				(type default)
			)
			(layer "F.Fab")
		)
		(fp_line
			(start 0.67945 -0.3048)
			(end 0.67945 0.3048)
			(stroke
				(width 0.1)
				(type default)
			)
			(layer "F.Fab")
		)
		(fp_line
			(start 0.12065 -0.3048)
			(end 0.67945 -0.3048)
			(stroke
				(width 0.1)
				(type default)
			)
			(layer "F.Fab")
		)
		(fp_line
			(start 0.12065 -0.2794)
			(end 0.12065 -0.3048)
			(stroke
				(width 0.1)
				(type default)
			)
			(layer "F.Fab")
		)
		(fp_line
			(start -0.12065 -0.2794)
			(end 0.12065 -0.2794)
			(stroke
				(width 0.1)
				(type default)
			)
			(layer "F.Fab")
		)
		(fp_line
			(start 0.120396 0.2794)
			(end -0.12065 0.2794)
			(stroke
				(width 0.1)
				(type default)
			)
			(layer "F.Fab")
		)
		(fp_line
			(start -0.12065 0.2794)
			(end -0.12065 0.3048)
			(stroke
				(width 0.1)
				(type default)
			)
			(layer "F.Fab")
		)
		(fp_line
			(start 0.67945 0.3048)
			(end 0.120396 0.3048)
			(stroke
				(width 0.1)
				(type default)
			)
			(layer "F.Fab")
		)
		(fp_line
			(start 0.120396 0.3048)
			(end 0.120396 0.2794)
			(stroke
				(width 0.1)
				(type default)
			)
			(layer "F.Fab")
		)
		(fp_line
			(start -0.12065 0.3048)
			(end -0.67945 0.3048)
			(stroke
				(width 0.1)
				(type default)
			)
			(layer "F.Fab")
		)
		(fp_line
			(start -0.67945 0.3048)
			(end -0.67945 -0.305054)
			(stroke
				(width 0.1)
				(type default)
			)
			(layer "F.Fab")
		)
		(pad "1" smd circle
			(at -0.40005 0 90)
			(size 0 0)
			(layers "F.Cu" "F.Mask" "F.Paste")
			(net "P3V3_OCP_SFF_R")
		)
		(pad "2" smd circle
			(at 0.40005 0 90)
			(size 0 0)
			(layers "F.Cu" "F.Mask" "F.Paste")
			(net "GND")
		)
	)
)
